# BASEBOARD_FAB2 (Tioga Pass) — schematic netlist excerpt (pin names and nets, part order shuffled) for the footprints in the layout excerpt that follows; sources: Cadence DE-HDL packaged netlist, KiCad conversion of Wiwynn_Tioga_Pass_MB.brd

R2T21  RES  2.2 1.0% CHIP  pkg 0603  page 101 : A = P3V3_STBY_MNG ; B = P3V3_STBY_MNG_CPU
C1M30  CAP_A  0.01UF 25V 10% X7R  pkg 0402V  page 112 : A = P3V3_STBY ; B = GND
C9L14  CAP  10UF 16V 10% X6S  pkg 0805  page 227 : A = VR_FET_SW_P12V_STBY_PVDDQ_KLM ; B = GND

(kicad_pcb
	(version 20260206)
	(generator "pcbnew")
	(generator_version "10.0")
	(general
		(thickness 1.6)
		(legacy_teardrops no)
	)
	(paper "A4")
	(title_block
		(title "Wiwynn_Tioga_Pass_MB.brd")
		(comment 1 "Tioga Pass / footprints 3837-3839 of 4770")
	)
	(layers
		(0 "F.Cu" signal "TOP")
		(4 "In1.Cu" signal "L2GND")
		(6 "In2.Cu" signal "L3")
		(8 "In3.Cu" signal "L4GND")
		(10 "In4.Cu" signal "L5")
		(12 "In5.Cu" signal "L6GND")
		(14 "In6.Cu" signal "L7VCC")
		(16 "In7.Cu" signal "L8VCC")
		(18 "In8.Cu" signal "L9GND")
		(20 "In9.Cu" signal "L10")
		(22 "In10.Cu" signal "L11GND")
		(24 "In11.Cu" signal "L12")
		(26 "In12.Cu" signal "L13GND")
		(2 "B.Cu" signal "BOTTOM")
		(9 "F.Adhes" user "F.Adhesive")
		(11 "B.Adhes" user "B.Adhesive")
		(13 "F.Paste" user "Package Geometry/Pastemask Top")
		(15 "B.Paste" user "Package Geometry/Pastemask Bottom")
		(5 "F.SilkS" user "Ref Des/Silkscreen Top")
		(7 "B.SilkS" user "Ref Des/Silkscreen Bottom")
		(1 "F.Mask" user "Board Geometry/Soldermask Top")
		(3 "B.Mask" user "Board Geometry/Soldermask Bottom")
		(17 "Dwgs.User" user "User.Drawings")
		(19 "Cmts.User" user "User.Comments")
		(21 "Eco1.User" user "User.Eco1")
		(23 "Eco2.User" user "User.Eco2")
		(25 "Edge.Cuts" user "Board Geometry/Outline")
		(27 "Margin" user)
		(31 "F.CrtYd" user "Package Geometry/Place Bound Top")
		(29 "B.CrtYd" user "Package Geometry/Place Bound Bottom")
		(35 "F.Fab" user "Ref Des/Assembly Top")
		(33 "B.Fab" user "Ref Des/Assembly Bottom")
	)
	(footprint ""
		(layer "B.Cu")
		(at 1.3462 -148.336 90)
		(property "Reference" "C9L14"
			(at 0 0 90)
			(layer "B.SilkS")
			(hide yes)
			(effects
				(font
					(size 1.27 1.27)
				)
				(justify mirror)
			)
		)
		(property "Value" ""
			(at 0 0 90)
			(layer "B.Fab")
			(effects
				(font
					(size 1.27 1.27)
				)
				(justify mirror)
			)
		)
		(duplicate_pad_numbers_are_jumpers no)
		(fp_rect
			(start -0.7239 -0.2159)
			(end 0.7239 1.9939)
			(stroke
				(width 0)
				(type default)
			)
			(fill no)
			(layer "B.CrtYd")
		)
		(fp_line
			(start 0.7239 -0.2159)
			(end 0.7239 1.9939)
			(stroke
				(width 0.1)
				(type default)
			)
			(layer "B.Fab")
		)
		(fp_line
			(start -0.7239 -0.2159)
			(end 0.7239 -0.2159)
			(stroke
				(width 0.1)
				(type default)
			)
			(layer "B.Fab")
		)
		(fp_line
			(start 0.7239 1.9939)
			(end -0.7239 1.9939)
			(stroke
				(width 0.1)
				(type default)
			)
			(layer "B.Fab")
		)
		(fp_line
			(start -0.7239 1.9939)
			(end -0.7239 -0.2159)
			(stroke
				(width 0.1)
				(type default)
			)
			(layer "B.Fab")
		)
		(pad "1" smd rect
			(at 0 0 270)
			(size 1.27 1.016)
			(layers "B.Cu" "B.Mask" "B.Paste")
			(net "VR_FET_SW_P12V_STBY_PVDDQ_KLM")
		)
		(pad "2" smd rect
			(at 0 1.778 270)
			(size 1.27 1.016)
			(layers "B.Cu" "B.Mask" "B.Paste")
			(net "GND")
		)
		(zone
			(layer "B.Cu")
			(hatch none 0.5)
			(connect_pads
				(clearance 0)
			)
			(min_thickness 0.25)
			(keepout
				(tracks not_allowed)
				(vias allowed)
				(pads allowed)
				(copperpour not_allowed)
				(footprints allowed)
			)
			(placement
				(enabled no)
				(sheetname "")
			)
			(fill
				(thermal_gap 0.5)
				(thermal_bridge_width 0.5)
				(island_removal_mode 0)
			)
			(polygon
				(pts
					(xy 1.8542 -147.701) (xy 2.6162 -147.701) (xy 2.6162 -148.971) (xy 1.8542 -148.971)
				)
			)
		)
	)
	(footprint ""
		(layer "B.Cu")
		(at 458.2414 -130.9624 90)
		(property "Reference" "C1M30"
			(at 0 0 90)
			(layer "B.SilkS")
			(hide yes)
			(effects
				(font
					(size 1.27 1.27)
				)
				(justify mirror)
			)
		)
		(property "Value" ""
			(at 0 0 90)
			(layer "B.Fab")
			(effects
				(font
					(size 1.27 1.27)
				)
				(justify mirror)
			)
		)
		(duplicate_pad_numbers_are_jumpers no)
		(fp_poly
			(pts
				(xy -0.3048 -0.1016) (xy -0.3048 0.9906) (xy 0.3048 0.9906) (xy 0.3048 -0.1016)
			)
			(stroke
				(width 0)
				(type default)
			)
			(fill no)
			(layer "B.CrtYd")
		)
		(fp_line
			(start 0.3048 -0.1016)
			(end 0.3048 0.9906)
			(stroke
				(width 0.1)
				(type default)
			)
			(layer "B.Fab")
		)
		(fp_line
			(start -0.3048 -0.1016)
			(end 0.3048 -0.1016)
			(stroke
				(width 0.1)
				(type default)
			)
			(layer "B.Fab")
		)
		(fp_line
			(start 0.3048 0.9906)
			(end -0.3048 0.9906)
			(stroke
				(width 0.1)
				(type default)
			)
			(layer "B.Fab")
		)
		(fp_line
			(start -0.3048 0.9906)
			(end -0.3048 -0.1016)
			(stroke
				(width 0.1)
				(type default)
			)
			(layer "B.Fab")
		)
		(pad "1" smd rect
			(at 0 0 270)
			(size 0.508 0.508)
			(layers "B.Cu" "B.Mask" "B.Paste")
			(net "P3V3_STBY")
		)
		(pad "2" smd rect
			(at 0 0.889 270)
			(size 0.508 0.508)
			(layers "B.Cu" "B.Mask" "B.Paste")
			(net "GND")
		)
		(zone
			(layer "B.Cu")
			(hatch none 0.5)
			(connect_pads
				(clearance 0)
			)
			(min_thickness 0.25)
			(keepout
				(tracks allowed)
				(vias not_allowed)
				(pads allowed)
				(copperpour not_allowed)
				(footprints allowed)
			)
			(placement
				(enabled no)
				(sheetname "")
			)
			(fill
				(thermal_gap 0.5)
				(thermal_bridge_width 0.5)
				(island_removal_mode 0)
			)
			(polygon
				(pts
					(xy 458.4954 -131.2164) (xy 458.4954 -130.7084) (xy 458.8764 -130.7084) (xy 458.8764 -131.2164)
				)
			)
		)
		(zone
			(layer "B.Cu")
			(hatch none 0.5)
			(connect_pads
				(clearance 0)
			)
			(min_thickness 0.25)
			(keepout
				(tracks not_allowed)
				(vias allowed)
				(pads allowed)
				(copperpour not_allowed)
				(footprints allowed)
			)
			(placement
				(enabled no)
				(sheetname "")
			)
			(fill
				(thermal_gap 0.5)
				(thermal_bridge_width 0.5)
				(island_removal_mode 0)
			)
			(polygon
				(pts
					(xy 458.8764 -131.2164) (xy 458.8764 -130.7084) (xy 458.4954 -130.7084) (xy 458.4954 -131.2164)
				)
			)
		)
	)
	(footprint ""
		(layer "B.Cu")
		(at 481.364798 -28.131008)
		(property "Reference" "R2T21"
			(at 0 0 0)
			(layer "B.SilkS")
			(hide yes)
			(effects
				(font
					(size 1.27 1.27)
				)
				(justify mirror)
			)
		)
		(property "Value" ""
			(at 0 0 0)
			(layer "B.Fab")
			(effects
				(font
					(size 1.27 1.27)
				)
				(justify mirror)
			)
		)
		(duplicate_pad_numbers_are_jumpers no)
		(fp_poly
			(pts
				(xy 0.4953 -0.2032) (xy -0.4953 -0.2032) (xy -0.4953 1.6002) (xy 0.4953 1.6002)
			)
			(stroke
				(width 0)
				(type default)
			)
			(fill no)
			(layer "B.CrtYd")
		)
		(fp_line
			(start -0.4953 -0.2032)
			(end -0.4953 1.6002)
			(stroke
				(width 0.1)
				(type default)
			)
			(layer "B.Fab")
		)
		(fp_line
			(start -0.4953 1.6002)
			(end 0.4953 1.6002)
			(stroke
				(width 0.1)
				(type default)
			)
			(layer "B.Fab")
		)
		(fp_line
			(start 0.4953 -0.2032)
			(end -0.4953 -0.2032)
			(stroke
				(width 0.1)
				(type default)
			)
			(layer "B.Fab")
		)
		(fp_line
			(start 0.4953 1.6002)
			(end 0.4953 -0.2032)
			(stroke
				(width 0.1)
				(type default)
			)
			(layer "B.Fab")
		)
		(pad "1" smd rect
			(at 0 0 180)
			(size 0.762 0.889)
			(layers "B.Cu" "B.Mask" "B.Paste")
			(net "P3V3_STBY_MNG")
		)
		(pad "2" smd rect
			(at 0 1.397 180)
			(size 0.762 0.889)
			(layers "B.Cu" "B.Mask" "B.Paste")
			(net "P3V3_STBY_MNG_CPU")
		)
		(zone
			(layer "B.Cu")
			(hatch none 0.5)
			(connect_pads
				(clearance 0)
			)
			(min_thickness 0.25)
			(keepout
				(tracks allowed)
				(vias not_allowed)
				(pads allowed)
				(copperpour not_allowed)
				(footprints allowed)
			)
			(placement
				(enabled no)
				(sheetname "")
			)
			(fill
				(thermal_gap 0.5)
				(thermal_bridge_width 0.5)
				(island_removal_mode 0)
			)
			(polygon
				(pts
					(xy 480.983798 -27.178508) (xy 480.983798 -27.686508) (xy 481.745798 -27.686508) (xy 481.745798 -27.178508)
				)
			)
		)
		(zone
			(layer "B.Cu")
			(hatch none 0.5)
			(connect_pads
				(clearance 0)
			)
			(min_thickness 0.25)
			(keepout
				(tracks not_allowed)
				(vias allowed)
				(pads allowed)
				(copperpour not_allowed)
				(footprints allowed)
			)
			(placement
				(enabled no)
				(sheetname "")
			)
			(fill
				(thermal_gap 0.5)
				(thermal_bridge_width 0.5)
				(island_removal_mode 0)
			)
			(polygon
				(pts
					(xy 481.745798 -27.178508) (xy 481.745798 -27.686508) (xy 480.983798 -27.686508) (xy 480.983798 -27.178508)
				)
			)
		)
	)
)
